# T6G (Grand Teton) — schematic netlist excerpt (pin names and nets, part order shuffled) for the footprints in the layout excerpt that follows; sources: Cadence DE-HDL packaged netlist, KiCad conversion of 04192023_DAF0TMB3IC0_F0TG_MB_C_brd_V02_OCP.brd

PC2157  Q_CAP  39PF 50V 5% NPO  pkg 0402  page 135 : A = P3V3_OCP_MODE_1 ; B = GND

Q9000  MOSFET_NCH_DUAL  PJT138K IC  pkg SOT363XD  page 123
  S1  = GND
  G1  = PRSNT_CABLE_SWB_B1_N
  D2  = PRSNT_CABLE_SWB_B1_ISO_N
  S2  = GND
  G2  = PRSNT_CABLE_SWB_B1
  D1  = PRSNT_CABLE_SWB_B1

(kicad_pcb
	(version 20260206)
	(generator "pcbnew")
	(generator_version "10.0")
	(general
		(thickness 1.6)
		(legacy_teardrops no)
	)
	(paper "A4")
	(title_block
		(title "04192023_DAF0TMB3IC0_F0TG_MB_C_brd_V02_OCP.brd")
		(comment 1 "Grand Teton / footprints 2573-2574 of 8354")
	)
	(layers
		(0 "F.Cu" signal "TOP")
		(4 "In1.Cu" signal "GND")
		(6 "In2.Cu" signal "IN1")
		(8 "In3.Cu" signal "GND1")
		(10 "In4.Cu" signal "IN2")
		(12 "In5.Cu" signal "GND2")
		(14 "In6.Cu" signal "IN3")
		(16 "In7.Cu" signal "GND3")
		(18 "In8.Cu" signal "VCC")
		(20 "In9.Cu" signal "VCC1")
		(22 "In10.Cu" signal "GND4")
		(24 "In11.Cu" signal "IN4")
		(26 "In12.Cu" signal "GND5")
		(28 "In13.Cu" signal "IN5")
		(30 "In14.Cu" signal "GND6")
		(32 "In15.Cu" signal "IN6")
		(34 "In16.Cu" signal "GND7")
		(2 "B.Cu" signal "BOTTOM")
		(9 "F.Adhes" user "F.Adhesive")
		(11 "B.Adhes" user "B.Adhesive")
		(13 "F.Paste" user "Package Geometry/Pastemask Top")
		(15 "B.Paste" user "Package Geometry/Pastemask Bottom")
		(5 "F.SilkS" user "Ref Des/Silkscreen Top")
		(7 "B.SilkS" user "Ref Des/Silkscreen Bottom")
		(1 "F.Mask" user "Board Geometry/Soldermask Top")
		(3 "B.Mask" user "Board Geometry/Soldermask Bottom")
		(17 "Dwgs.User" user "User.Drawings")
		(19 "Cmts.User" user "User.Comments")
		(21 "Eco1.User" user "User.Eco1")
		(23 "Eco2.User" user "User.Eco2")
		(25 "Edge.Cuts" user "Board Geometry/Outline")
		(27 "Margin" user)
		(31 "F.CrtYd" user "Package Geometry/Place Bound Top")
		(29 "B.CrtYd" user "Package Geometry/Place Bound Bottom")
		(35 "F.Fab" user "Ref Des/Assembly Top")
		(33 "B.Fab" user "Ref Des/Assembly Bottom")
	)
	(footprint ""
		(layer "F.Cu")
		(at 362.984288 -415.729166 90)
		(property "Reference" "Q9000"
			(at -1.462278 1.708658 90)
			(unlocked yes)
			(layer "F.SilkS")
			(effects
				(font
					(size 0.7874 0.5842)
					(thickness 0.1524)
				)
				(justify left)
			)
		)
		(property "Value" ""
			(at 0 0 90)
			(layer "F.Fab")
			(effects
				(font
					(size 1.27 1.27)
				)
			)
		)
		(duplicate_pad_numbers_are_jumpers no)
		(fp_line
			(start 1.332738 -1.100074)
			(end 1.332738 1.100074)
			(stroke
				(width 0.1524)
				(type default)
			)
			(layer "F.SilkS")
		)
		(fp_line
			(start 0.4826 -1.100074)
			(end 1.332738 -1.100074)
			(stroke
				(width 0.1524)
				(type default)
			)
			(layer "F.SilkS")
		)
		(fp_line
			(start -0.4826 -1.100074)
			(end 0 -0.541274)
			(stroke
				(width 0.1524)
				(type default)
			)
			(layer "F.SilkS")
		)
		(fp_line
			(start -1.332738 -1.100074)
			(end -0.4826 -1.100074)
			(stroke
				(width 0.1524)
				(type default)
			)
			(layer "F.SilkS")
		)
		(fp_line
			(start 0 -0.541274)
			(end 0.4826 -1.100074)
			(stroke
				(width 0.1524)
				(type default)
			)
			(layer "F.SilkS")
		)
		(fp_line
			(start 1.332738 1.100074)
			(end -1.332738 1.100074)
			(stroke
				(width 0.1524)
				(type default)
			)
			(layer "F.SilkS")
		)
		(fp_line
			(start -1.332738 1.100074)
			(end -1.332738 -1.100074)
			(stroke
				(width 0.1524)
				(type default)
			)
			(layer "F.SilkS")
		)
		(fp_poly
			(pts
				(xy -2.2352 -0.298958) (xy -2.2352 -1.001014) (xy -1.533144 -0.649986)
			)
			(stroke
				(width 0)
				(type default)
			)
			(fill yes)
			(layer "F.SilkS")
		)
		(fp_line
			(start 0.674878 -1.100074)
			(end 0.674878 1.100074)
			(stroke
				(width 0.1)
				(type default)
			)
			(layer "F.Fab")
		)
		(fp_line
			(start -0.674878 -1.100074)
			(end 0.674878 -1.100074)
			(stroke
				(width 0.1)
				(type default)
			)
			(layer "F.Fab")
		)
		(fp_line
			(start 0.674878 1.100074)
			(end -0.674878 1.100074)
			(stroke
				(width 0.1)
				(type default)
			)
			(layer "F.Fab")
		)
		(fp_line
			(start -0.674878 1.100074)
			(end -0.674878 -1.100074)
			(stroke
				(width 0.1)
				(type default)
			)
			(layer "F.Fab")
		)
		(fp_poly
			(pts
				(xy -2.2352 -0.298958) (xy -2.2352 -1.001014) (xy -1.533144 -0.649986)
			)
			(stroke
				(width 0)
				(type default)
			)
			(fill yes)
			(layer "F.Fab")
		)
		(pad "1" smd rect
			(at -0.94996 -0.649986 180)
			(size 0.4318 0.508)
			(layers "F.Cu" "F.Mask" "F.Paste")
			(net "GND")
		)
		(pad "2" smd rect
			(at -0.94996 0 180)
			(size 0.4318 0.508)
			(layers "F.Cu" "F.Mask" "F.Paste")
			(net "PRSNT_CABLE_SWB_B1_N")
		)
		(pad "3" smd rect
			(at -0.94996 0.649986 180)
			(size 0.4318 0.508)
			(layers "F.Cu" "F.Mask" "F.Paste")
			(net "PRSNT_CABLE_SWB_B1_ISO_N")
		)
		(pad "4" smd rect
			(at 0.94996 0.649986 180)
			(size 0.4318 0.508)
			(layers "F.Cu" "F.Mask" "F.Paste")
			(net "GND")
		)
		(pad "5" smd rect
			(at 0.94996 0 180)
			(size 0.4318 0.508)
			(layers "F.Cu" "F.Mask" "F.Paste")
			(net "PRSNT_CABLE_SWB_B1")
		)
		(pad "6" smd rect
			(at 0.94996 -0.649986 180)
			(size 0.4318 0.508)
			(layers "F.Cu" "F.Mask" "F.Paste")
			(net "PRSNT_CABLE_SWB_B1")
		)
	)
	(footprint ""
		(layer "F.Cu")
		(at 421.54094 -101.270308 -90)
		(property "Reference" "PC2157"
			(at 0 0 270)
			(layer "F.SilkS")
			(hide yes)
			(effects
				(font
					(size 1.27 1.27)
				)
			)
		)
		(property "Value" ""
			(at 0 0 270)
			(layer "F.Fab")
			(effects
				(font
					(size 1.27 1.27)
				)
			)
		)
		(duplicate_pad_numbers_are_jumpers no)
		(fp_line
			(start -0.7874 0.4064)
			(end -0.7874 -0.4064)
			(stroke
				(width 0.1524)
				(type default)
			)
			(layer "F.SilkS")
		)
		(fp_line
			(start 0.7874 0.4064)
			(end -0.7874 0.4064)
			(stroke
				(width 0.1524)
				(type default)
			)
			(layer "F.SilkS")
		)
		(fp_line
			(start -0.7874 -0.4064)
			(end 0.7874 -0.4064)
			(stroke
				(width 0.1524)
				(type default)
			)
			(layer "F.SilkS")
		)
		(fp_line
			(start 0.7874 -0.4064)
			(end 0.7874 0.4064)
			(stroke
				(width 0.1524)
				(type default)
			)
			(layer "F.SilkS")
		)
		(fp_line
			(start -0.67945 0.3048)
			(end -0.67945 -0.305054)
			(stroke
				(width 0.1)
				(type default)
			)
			(layer "F.Fab")
		)
		(fp_line
			(start -0.12065 0.3048)
			(end -0.67945 0.3048)
			(stroke
				(width 0.1)
				(type default)
			)
			(layer "F.Fab")
		)
		(fp_line
			(start 0.120396 0.3048)
			(end 0.120396 0.2794)
			(stroke
				(width 0.1)
				(type default)
			)
			(layer "F.Fab")
		)
		(fp_line
			(start 0.67945 0.3048)
			(end 0.120396 0.3048)
			(stroke
				(width 0.1)
				(type default)
			)
			(layer "F.Fab")
		)
		(fp_line
			(start -0.12065 0.2794)
			(end -0.12065 0.3048)
			(stroke
				(width 0.1)
				(type default)
			)
			(layer "F.Fab")
		)
		(fp_line
			(start 0.120396 0.2794)
			(end -0.12065 0.2794)
			(stroke
				(width 0.1)
				(type default)
			)
			(layer "F.Fab")
		)
		(fp_line
			(start -0.12065 -0.2794)
			(end 0.12065 -0.2794)
			(stroke
				(width 0.1)
				(type default)
			)
			(layer "F.Fab")
		)
		(fp_line
			(start 0.12065 -0.2794)
			(end 0.12065 -0.3048)
			(stroke
				(width 0.1)
				(type default)
			)
			(layer "F.Fab")
		)
		(fp_line
			(start 0.12065 -0.3048)
			(end 0.67945 -0.3048)
			(stroke
				(width 0.1)
				(type default)
			)
			(layer "F.Fab")
		)
		(fp_line
			(start 0.67945 -0.3048)
			(end 0.67945 0.3048)
			(stroke
				(width 0.1)
				(type default)
			)
			(layer "F.Fab")
		)
		(fp_line
			(start -0.67945 -0.305054)
			(end -0.12065 -0.305054)
			(stroke
				(width 0.1)
				(type default)
			)
			(layer "F.Fab")
		)
		(fp_line
			(start -0.12065 -0.305054)
			(end -0.12065 -0.2794)
			(stroke
				(width 0.1)
				(type default)
			)
			(layer "F.Fab")
		)
		(pad "1" smd circle
			(at -0.40005 0 270)
			(size 0 0)
			(layers "F.Cu" "F.Mask" "F.Paste")
			(net "P3V3_OCP_MODE_1")
		)
		(pad "2" smd circle
			(at 0.40005 0 270)
			(size 0 0)
			(layers "F.Cu" "F.Mask" "F.Paste")
			(net "GND")
		)
	)
)
